(kicad_pcb
	(version 20260206)
	(generator "pcbnew")
	(generator_version "10.0")
	(general
		(thickness 1.6)
		(legacy_teardrops no)
	)
	(paper "A4")
	(title_block
		(title "01162023_DA0F0TEBIF0_F0T_Expander_BD_F_brd_V02_OCP.brd")
		(comment 1 "Grand Teton / footprints 9631-9640 of 9728")
	)
	(layers
		(0 "F.Cu" signal "TOP")
		(4 "In1.Cu" signal "GND")
		(6 "In2.Cu" signal "VCC")
		(8 "In3.Cu" signal "VCC1")
		(10 "In4.Cu" signal "GND1")
		(12 "In5.Cu" signal "IN1")
		(14 "In6.Cu" signal "GND2")
		(16 "In7.Cu" signal "IN2")
		(18 "In8.Cu" signal "GND3")
		(20 "In9.Cu" signal "IN3")
		(22 "In10.Cu" signal "GND4")
		(24 "In11.Cu" signal "IN4")
		(26 "In12.Cu" signal "GND5")
		(28 "In13.Cu" signal "IN5")
		(30 "In14.Cu" signal "GND6")
		(32 "In15.Cu" signal "IN6")
		(34 "In16.Cu" signal "GND7")
		(2 "B.Cu" signal "BOTTOM")
		(9 "F.Adhes" user "F.Adhesive")
		(11 "B.Adhes" user "B.Adhesive")
		(13 "F.Paste" user "Package Geometry/Pastemask Top")
		(15 "B.Paste" user "Package Geometry/Pastemask Bottom")
		(5 "F.SilkS" user "Ref Des/Silkscreen Top")
		(7 "B.SilkS" user "Ref Des/Silkscreen Bottom")
		(1 "F.Mask" user "Board Geometry/Soldermask Top")
		(3 "B.Mask" user "Board Geometry/Soldermask Bottom")
		(17 "Dwgs.User" user "User.Drawings")
		(19 "Cmts.User" user "User.Comments")
		(21 "Eco1.User" user "User.Eco1")
		(23 "Eco2.User" user "User.Eco2")
		(25 "Edge.Cuts" user "Board Geometry/Outline")
		(27 "Margin" user)
		(31 "F.CrtYd" user "Package Geometry/Place Bound Top")
		(29 "B.CrtYd" user "Package Geometry/Place Bound Bottom")
		(35 "F.Fab" user "Ref Des/Assembly Top")
		(33 "B.Fab" user "Ref Des/Assembly Bottom")
	)
	(footprint ""
		(layer "B.Cu")
		(at 48.72482 -297.79976 -90)
		(property "Reference" "C1123"
			(at 0 0 90)
			(layer "B.SilkS")
			(hide yes)
			(effects
				(font
					(size 1.27 1.27)
				)
				(justify mirror)
			)
		)
		(property "Value" ""
			(at 0 0 90)
			(layer "B.Fab")
			(effects
				(font
					(size 1.27 1.27)
				)
				(justify mirror)
			)
		)
		(duplicate_pad_numbers_are_jumpers no)
		(fp_line
			(start -0.299974 0.150114)
			(end 0.299974 0.150114)
			(stroke
				(width 0.1)
				(type default)
			)
			(layer "B.Fab")
		)
		(fp_line
			(start 0.299974 0.150114)
			(end 0.299974 -0.150114)
			(stroke
				(width 0.1)
				(type default)
			)
			(layer "B.Fab")
		)
		(fp_line
			(start -0.299974 -0.150114)
			(end -0.299974 0.150114)
			(stroke
				(width 0.1)
				(type default)
			)
			(layer "B.Fab")
		)
		(fp_line
			(start 0.299974 -0.150114)
			(end -0.299974 -0.150114)
			(stroke
				(width 0.1)
				(type default)
			)
			(layer "B.Fab")
		)
		(pad "1" smd rect
			(at 0.2667 0 90)
			(size 0.3048 0.381)
			(layers "B.Cu" "B.Mask" "B.Paste")
			(net "P0V8_PEX0")
		)
		(pad "2" smd rect
			(at -0.2667 0 90)
			(size 0.3048 0.381)
			(layers "B.Cu" "B.Mask" "B.Paste")
			(net "GND")
		)
	)
	(footprint ""
		(layer "B.Cu")
		(at 119.347488 -303.141634)
		(property "Reference" "PR79"
			(at 0 0 0)
			(layer "B.SilkS")
			(hide yes)
			(effects
				(font
					(size 1.27 1.27)
				)
				(justify mirror)
			)
		)
		(property "Value" ""
			(at 0 0 0)
			(layer "B.Fab")
			(effects
				(font
					(size 1.27 1.27)
				)
				(justify mirror)
			)
		)
		(duplicate_pad_numbers_are_jumpers no)
		(fp_line
			(start -0.7874 -0.4064)
			(end -0.7874 0.4064)
			(stroke
				(width 0.1524)
				(type default)
			)
			(layer "B.SilkS")
		)
		(fp_line
			(start -0.7874 0.4064)
			(end 0.7874 0.4064)
			(stroke
				(width 0.1524)
				(type default)
			)
			(layer "B.SilkS")
		)
		(fp_line
			(start 0.7874 -0.4064)
			(end -0.7874 -0.4064)
			(stroke
				(width 0.1524)
				(type default)
			)
			(layer "B.SilkS")
		)
		(fp_line
			(start 0.7874 0.4064)
			(end 0.7874 -0.4064)
			(stroke
				(width 0.1524)
				(type default)
			)
			(layer "B.SilkS")
		)
		(fp_line
			(start -0.67945 -0.3048)
			(end -0.67945 0.3048)
			(stroke
				(width 0.1)
				(type default)
			)
			(layer "B.Fab")
		)
		(fp_line
			(start -0.67945 0.3048)
			(end -0.120396 0.3048)
			(stroke
				(width 0.1)
				(type default)
			)
			(layer "B.Fab")
		)
		(fp_line
			(start -0.12065 -0.3048)
			(end -0.67945 -0.3048)
			(stroke
				(width 0.1)
				(type default)
			)
			(layer "B.Fab")
		)
		(fp_line
			(start -0.12065 -0.2794)
			(end -0.12065 -0.3048)
			(stroke
				(width 0.1)
				(type default)
			)
			(layer "B.Fab")
		)
		(fp_line
			(start -0.120396 0.2794)
			(end 0.12065 0.2794)
			(stroke
				(width 0.1)
				(type default)
			)
			(layer "B.Fab")
		)
		(fp_line
			(start -0.120396 0.3048)
			(end -0.120396 0.2794)
			(stroke
				(width 0.1)
				(type default)
			)
			(layer "B.Fab")
		)
		(fp_line
			(start 0.12065 -0.305054)
			(end 0.12065 -0.2794)
			(stroke
				(width 0.1)
				(type default)
			)
			(layer "B.Fab")
		)
		(fp_line
			(start 0.12065 -0.2794)
			(end -0.12065 -0.2794)
			(stroke
				(width 0.1)
				(type default)
			)
			(layer "B.Fab")
		)
		(fp_line
			(start 0.12065 0.2794)
			(end 0.12065 0.3048)
			(stroke
				(width 0.1)
				(type default)
			)
			(layer "B.Fab")
		)
		(fp_line
			(start 0.12065 0.3048)
			(end 0.67945 0.3048)
			(stroke
				(width 0.1)
				(type default)
			)
			(layer "B.Fab")
		)
		(fp_line
			(start 0.67945 -0.305054)
			(end 0.12065 -0.305054)
			(stroke
				(width 0.1)
				(type default)
			)
			(layer "B.Fab")
		)
		(fp_line
			(start 0.67945 0.3048)
			(end 0.67945 -0.305054)
			(stroke
				(width 0.1)
				(type default)
			)
			(layer "B.Fab")
		)
		(pad "1" smd circle
			(at 0.40005 0 180)
			(size 0 0)
			(layers "B.Cu" "B.Mask" "B.Paste")
			(net "P0V8_PEX1")
		)
		(pad "2" smd circle
			(at -0.40005 0 180)
			(size 0 0)
			(layers "B.Cu" "B.Mask" "B.Paste")
			(net "SH_P0V8_PEX1_VSEN1_L")
		)
	)
	(footprint ""
		(layer "B.Cu")
		(at 51.099974 -288.299906 90)
		(property "Reference" "C2930"
			(at 0 0 90)
			(layer "B.SilkS")
			(hide yes)
			(effects
				(font
					(size 1.27 1.27)
				)
				(justify mirror)
			)
		)
		(property "Value" ""
			(at 0 0 90)
			(layer "B.Fab")
			(effects
				(font
					(size 1.27 1.27)
				)
				(justify mirror)
			)
		)
		(duplicate_pad_numbers_are_jumpers no)
		(fp_line
			(start 0.299974 -0.150114)
			(end -0.299974 -0.150114)
			(stroke
				(width 0.1)
				(type default)
			)
			(layer "B.Fab")
		)
		(fp_line
			(start -0.299974 -0.150114)
			(end -0.299974 0.150114)
			(stroke
				(width 0.1)
				(type default)
			)
			(layer "B.Fab")
		)
		(fp_line
			(start 0.299974 0.150114)
			(end 0.299974 -0.150114)
			(stroke
				(width 0.1)
				(type default)
			)
			(layer "B.Fab")
		)
		(fp_line
			(start -0.299974 0.150114)
			(end 0.299974 0.150114)
			(stroke
				(width 0.1)
				(type default)
			)
			(layer "B.Fab")
		)
		(pad "1" smd rect
			(at 0.2667 0 270)
			(size 0.3048 0.381)
			(layers "B.Cu" "B.Mask" "B.Paste")
			(net "P1V25_PEX0")
		)
		(pad "2" smd rect
			(at -0.2667 0 270)
			(size 0.3048 0.381)
			(layers "B.Cu" "B.Mask" "B.Paste")
			(net "GND")
		)
	)
	(footprint ""
		(layer "B.Cu")
		(at 294.22471 -297.79976 90)
		(property "Reference" "C1645"
			(at 0 0 90)
			(layer "B.SilkS")
			(hide yes)
			(effects
				(font
					(size 1.27 1.27)
				)
				(justify mirror)
			)
		)
		(property "Value" ""
			(at 0 0 90)
			(layer "B.Fab")
			(effects
				(font
					(size 1.27 1.27)
				)
				(justify mirror)
			)
		)
		(duplicate_pad_numbers_are_jumpers no)
		(fp_line
			(start 0.299974 -0.150114)
			(end -0.299974 -0.150114)
			(stroke
				(width 0.1)
				(type default)
			)
			(layer "B.Fab")
		)
		(fp_line
			(start -0.299974 -0.150114)
			(end -0.299974 0.150114)
			(stroke
				(width 0.1)
				(type default)
			)
			(layer "B.Fab")
		)
		(fp_line
			(start 0.299974 0.150114)
			(end 0.299974 -0.150114)
			(stroke
				(width 0.1)
				(type default)
			)
			(layer "B.Fab")
		)
		(fp_line
			(start -0.299974 0.150114)
			(end 0.299974 0.150114)
			(stroke
				(width 0.1)
				(type default)
			)
			(layer "B.Fab")
		)
		(pad "1" smd rect
			(at 0.2667 0 270)
			(size 0.3048 0.381)
			(layers "B.Cu" "B.Mask" "B.Paste")
			(net "P0V8_PEX2")
		)
		(pad "2" smd rect
			(at -0.2667 0 270)
			(size 0.3048 0.381)
			(layers "B.Cu" "B.Mask" "B.Paste")
			(net "GND")
		)
	)
	(footprint ""
		(layer "B.Cu")
		(at 350.757744 -321.14617 -90)
		(property "Reference" "R6536"
			(at 0 0 90)
			(layer "B.SilkS")
			(hide yes)
			(effects
				(font
					(size 1.27 1.27)
				)
				(justify mirror)
			)
		)
		(property "Value" ""
			(at 0 0 90)
			(layer "B.Fab")
			(effects
				(font
					(size 1.27 1.27)
				)
				(justify mirror)
			)
		)
		(duplicate_pad_numbers_are_jumpers no)
		(fp_line
			(start -0.7874 0.4064)
			(end 0.7874 0.4064)
			(stroke
				(width 0.1524)
				(type default)
			)
			(layer "B.SilkS")
		)
		(fp_line
			(start 0.7874 0.4064)
			(end 0.7874 -0.4064)
			(stroke
				(width 0.1524)
				(type default)
			)
			(layer "B.SilkS")
		)
		(fp_line
			(start -0.7874 -0.4064)
			(end -0.7874 0.4064)
			(stroke
				(width 0.1524)
				(type default)
			)
			(layer "B.SilkS")
		)
		(fp_line
			(start 0.7874 -0.4064)
			(end -0.7874 -0.4064)
			(stroke
				(width 0.1524)
				(type default)
			)
			(layer "B.SilkS")
		)
		(fp_line
			(start -0.67945 0.3048)
			(end -0.120396 0.3048)
			(stroke
				(width 0.1)
				(type default)
			)
			(layer "B.Fab")
		)
		(fp_line
			(start -0.120396 0.3048)
			(end -0.120396 0.2794)
			(stroke
				(width 0.1)
				(type default)
			)
			(layer "B.Fab")
		)
		(fp_line
			(start 0.12065 0.3048)
			(end 0.67945 0.3048)
			(stroke
				(width 0.1)
				(type default)
			)
			(layer "B.Fab")
		)
		(fp_line
			(start 0.67945 0.3048)
			(end 0.67945 -0.305054)
			(stroke
				(width 0.1)
				(type default)
			)
			(layer "B.Fab")
		)
		(fp_line
			(start -0.120396 0.2794)
			(end 0.12065 0.2794)
			(stroke
				(width 0.1)
				(type default)
			)
			(layer "B.Fab")
		)
		(fp_line
			(start 0.12065 0.2794)
			(end 0.12065 0.3048)
			(stroke
				(width 0.1)
				(type default)
			)
			(layer "B.Fab")
		)
		(fp_line
			(start -0.12065 -0.2794)
			(end -0.12065 -0.3048)
			(stroke
				(width 0.1)
				(type default)
			)
			(layer "B.Fab")
		)
		(fp_line
			(start 0.12065 -0.2794)
			(end -0.12065 -0.2794)
			(stroke
				(width 0.1)
				(type default)
			)
			(layer "B.Fab")
		)
		(fp_line
			(start -0.67945 -0.3048)
			(end -0.67945 0.3048)
			(stroke
				(width 0.1)
				(type default)
			)
			(layer "B.Fab")
		)
		(fp_line
			(start -0.12065 -0.3048)
			(end -0.67945 -0.3048)
			(stroke
				(width 0.1)
				(type default)
			)
			(layer "B.Fab")
		)
		(fp_line
			(start 0.12065 -0.305054)
			(end 0.12065 -0.2794)
			(stroke
				(width 0.1)
				(type default)
			)
			(layer "B.Fab")
		)
		(fp_line
			(start 0.67945 -0.305054)
			(end 0.12065 -0.305054)
			(stroke
				(width 0.1)
				(type default)
			)
			(layer "B.Fab")
		)
		(pad "1" smd circle
			(at 0.40005 0 90)
			(size 0 0)
			(layers "B.Cu" "B.Mask" "B.Paste")
			(net "P0V8_SERDES_VDDA_PEX3")
		)
		(pad "2" smd circle
			(at -0.40005 0 90)
			(size 0 0)
			(layers "B.Cu" "B.Mask" "B.Paste")
			(net "P0V8_SERDES_VDDA_PEX3_C1")
		)
	)
	(footprint ""
		(layer "B.Cu")
		(at 10.641838 -272.550636 180)
		(property "Reference" "C4223"
			(at 0 0 0)
			(layer "B.SilkS")
			(hide yes)
			(effects
				(font
					(size 1.27 1.27)
				)
				(justify mirror)
			)
		)
		(property "Value" ""
			(at 0 0 0)
			(layer "B.Fab")
			(effects
				(font
					(size 1.27 1.27)
				)
				(justify mirror)
			)
		)
		(duplicate_pad_numbers_are_jumpers no)
		(fp_line
			(start 0.299974 0.150114)
			(end 0.299974 -0.150114)
			(stroke
				(width 0.1)
				(type default)
			)
			(layer "B.Fab")
		)
		(fp_line
			(start 0.299974 -0.150114)
			(end -0.299974 -0.150114)
			(stroke
				(width 0.1)
				(type default)
			)
			(layer "B.Fab")
		)
		(fp_line
			(start -0.299974 0.150114)
			(end 0.299974 0.150114)
			(stroke
				(width 0.1)
				(type default)
			)
			(layer "B.Fab")
		)
		(fp_line
			(start -0.299974 -0.150114)
			(end -0.299974 0.150114)
			(stroke
				(width 0.1)
				(type default)
			)
			(layer "B.Fab")
		)
		(pad "1" smd rect
			(at 0.2667 0)
			(size 0.3048 0.381)
			(layers "B.Cu" "B.Mask" "B.Paste")
			(net "P1V25_PEX0")
		)
		(pad "2" smd rect
			(at -0.2667 0)
			(size 0.3048 0.381)
			(layers "B.Cu" "B.Mask" "B.Paste")
			(net "GND")
		)
	)
	(footprint ""
		(layer "B.Cu")
		(at 49.149 -301.0154 180)
		(property "Reference" "C1110"
			(at 0 0 0)
			(layer "B.SilkS")
			(hide yes)
			(effects
				(font
					(size 1.27 1.27)
				)
				(justify mirror)
			)
		)
		(property "Value" ""
			(at 0 0 0)
			(layer "B.Fab")
			(effects
				(font
					(size 1.27 1.27)
				)
				(justify mirror)
			)
		)
		(duplicate_pad_numbers_are_jumpers no)
		(fp_line
			(start 0.299974 0.150114)
			(end 0.299974 -0.150114)
			(stroke
				(width 0.1)
				(type default)
			)
			(layer "B.Fab")
		)
		(fp_line
			(start 0.299974 -0.150114)
			(end -0.299974 -0.150114)
			(stroke
				(width 0.1)
				(type default)
			)
			(layer "B.Fab")
		)
		(fp_line
			(start -0.299974 0.150114)
			(end 0.299974 0.150114)
			(stroke
				(width 0.1)
				(type default)
			)
			(layer "B.Fab")
		)
		(fp_line
			(start -0.299974 -0.150114)
			(end -0.299974 0.150114)
			(stroke
				(width 0.1)
				(type default)
			)
			(layer "B.Fab")
		)
		(pad "1" smd rect
			(at 0.2667 0)
			(size 0.3048 0.381)
			(layers "B.Cu" "B.Mask" "B.Paste")
			(net "P0V8_PEX0")
		)
		(pad "2" smd rect
			(at -0.2667 0)
			(size 0.3048 0.381)
			(layers "B.Cu" "B.Mask" "B.Paste")
			(net "GND")
		)
	)
	(footprint ""
		(layer "B.Cu")
		(at 348.493842 -220.387164 -90)
		(property "Reference" "C2040"
			(at 0 0 90)
			(layer "B.SilkS")
			(hide yes)
			(effects
				(font
					(size 1.27 1.27)
				)
				(justify mirror)
			)
		)
		(property "Value" ""
			(at 0 0 90)
			(layer "B.Fab")
			(effects
				(font
					(size 1.27 1.27)
				)
				(justify mirror)
			)
		)
		(duplicate_pad_numbers_are_jumpers no)
		(fp_line
			(start -0.69215 0.2921)
			(end 0.69215 0.2921)
			(stroke
				(width 0.1524)
				(type default)
			)
			(layer "B.SilkS")
		)
		(fp_line
			(start 0.69215 0.2921)
			(end 0.69215 -0.2921)
			(stroke
				(width 0.1524)
				(type default)
			)
			(layer "B.SilkS")
		)
		(fp_line
			(start -0.69215 -0.2921)
			(end -0.69215 0.2921)
			(stroke
				(width 0.1524)
				(type default)
			)
			(layer "B.SilkS")
		)
		(fp_line
			(start 0.69215 -0.2921)
			(end -0.69215 -0.2921)
			(stroke
				(width 0.1524)
				(type default)
			)
			(layer "B.SilkS")
		)
		(fp_line
			(start -0.51435 0.2794)
			(end 0.51435 0.2794)
			(stroke
				(width 0.1)
				(type default)
			)
			(layer "B.Fab")
		)
		(fp_line
			(start 0.51435 0.2794)
			(end 0.51435 -0.2794)
			(stroke
				(width 0.1)
				(type default)
			)
			(layer "B.Fab")
		)
		(fp_line
			(start -0.51435 -0.2794)
			(end -0.51435 0.2794)
			(stroke
				(width 0.1)
				(type default)
			)
			(layer "B.Fab")
		)
		(fp_line
			(start 0.51435 -0.2794)
			(end -0.51435 -0.2794)
			(stroke
				(width 0.1)
				(type default)
			)
			(layer "B.Fab")
		)
		(pad "1" smd circle
			(at 0.40005 0 90)
			(size 0 0)
			(layers "B.Cu" "B.Mask" "B.Paste")
			(net "P3V3_FPGA_VCCIO1")
		)
		(pad "2" smd circle
			(at -0.40005 0 90)
			(size 0 0)
			(layers "B.Cu" "B.Mask" "B.Paste")
			(net "GND")
		)
		(zone
			(layer "B.Cu")
			(hatch none 0.5)
			(connect_pads
				(clearance 0)
			)
			(min_thickness 0.25)
			(keepout
				(tracks not_allowed)
				(vias allowed)
				(pads allowed)
				(copperpour not_allowed)
				(footprints allowed)
			)
			(placement
				(enabled no)
				(sheetname "")
			)
			(fill
				(thermal_gap 0.5)
				(thermal_bridge_width 0.5)
				(island_removal_mode 0)
			)
			(polygon
				(pts
					(xy 348.406212 -220.196664) (xy 348.348046 -220.288104) (xy 348.348046 -220.487494) (xy 348.406212 -220.577664)
					(xy 348.581472 -220.577664) (xy 348.639892 -220.487494) (xy 348.639892 -220.288104) (xy 348.581726 -220.196664)
				)
			)
		)
	)
	(footprint ""
		(layer "B.Cu")
		(at 408.899868 -288.299906 90)
		(property "Reference" "C3448"
			(at 0 0 90)
			(layer "B.SilkS")
			(hide yes)
			(effects
				(font
					(size 1.27 1.27)
				)
				(justify mirror)
			)
		)
		(property "Value" ""
			(at 0 0 90)
			(layer "B.Fab")
			(effects
				(font
					(size 1.27 1.27)
				)
				(justify mirror)
			)
		)
		(duplicate_pad_numbers_are_jumpers no)
		(fp_line
			(start 0.299974 -0.150114)
			(end -0.299974 -0.150114)
			(stroke
				(width 0.1)
				(type default)
			)
			(layer "B.Fab")
		)
		(fp_line
			(start -0.299974 -0.150114)
			(end -0.299974 0.150114)
			(stroke
				(width 0.1)
				(type default)
			)
			(layer "B.Fab")
		)
		(fp_line
			(start 0.299974 0.150114)
			(end 0.299974 -0.150114)
			(stroke
				(width 0.1)
				(type default)
			)
			(layer "B.Fab")
		)
		(fp_line
			(start -0.299974 0.150114)
			(end 0.299974 0.150114)
			(stroke
				(width 0.1)
				(type default)
			)
			(layer "B.Fab")
		)
		(pad "1" smd rect
			(at 0.2667 0 270)
			(size 0.3048 0.381)
			(layers "B.Cu" "B.Mask" "B.Paste")
			(net "P1V25_PEX3")
		)
		(pad "2" smd rect
			(at -0.2667 0 270)
			(size 0.3048 0.381)
			(layers "B.Cu" "B.Mask" "B.Paste")
			(net "GND")
		)
	)
	(footprint ""
		(layer "B.Cu")
		(at 237.631986 -354.235258)
		(property "Reference" "PR7150"
			(at 0 0 0)
			(layer "B.SilkS")
			(hide yes)
			(effects
				(font
					(size 1.27 1.27)
				)
				(justify mirror)
			)
		)
		(property "Value" ""
			(at 0 0 0)
			(layer "B.Fab")
			(effects
				(font
					(size 1.27 1.27)
				)
				(justify mirror)
			)
		)
		(duplicate_pad_numbers_are_jumpers no)
		(fp_line
			(start -0.7874 -0.4064)
			(end -0.7874 0.4064)
			(stroke
				(width 0.1524)
				(type default)
			)
			(layer "B.SilkS")
		)
		(fp_line
			(start -0.7874 0.4064)
			(end 0.7874 0.4064)
			(stroke
				(width 0.1524)
				(type default)
			)
			(layer "B.SilkS")
		)
		(fp_line
			(start 0.7874 -0.4064)
			(end -0.7874 -0.4064)
			(stroke
				(width 0.1524)
				(type default)
			)
			(layer "B.SilkS")
		)
		(fp_line
			(start 0.7874 0.4064)
			(end 0.7874 -0.4064)
			(stroke
				(width 0.1524)
				(type default)
			)
			(layer "B.SilkS")
		)
		(fp_line
			(start -0.67945 -0.3048)
			(end -0.67945 0.3048)
			(stroke
				(width 0.1)
				(type default)
			)
			(layer "B.Fab")
		)
		(fp_line
			(start -0.67945 0.3048)
			(end -0.120396 0.3048)
			(stroke
				(width 0.1)
				(type default)
			)
			(layer "B.Fab")
		)
		(fp_line
			(start -0.12065 -0.3048)
			(end -0.67945 -0.3048)
			(stroke
				(width 0.1)
				(type default)
			)
			(layer "B.Fab")
		)
		(fp_line
			(start -0.12065 -0.2794)
			(end -0.12065 -0.3048)
			(stroke
				(width 0.1)
				(type default)
			)
			(layer "B.Fab")
		)
		(fp_line
			(start -0.120396 0.2794)
			(end 0.12065 0.2794)
			(stroke
				(width 0.1)
				(type default)
			)
			(layer "B.Fab")
		)
		(fp_line
			(start -0.120396 0.3048)
			(end -0.120396 0.2794)
			(stroke
				(width 0.1)
				(type default)
			)
			(layer "B.Fab")
		)
		(fp_line
			(start 0.12065 -0.305054)
			(end 0.12065 -0.2794)
			(stroke
				(width 0.1)
				(type default)
			)
			(layer "B.Fab")
		)
		(fp_line
			(start 0.12065 -0.2794)
			(end -0.12065 -0.2794)
			(stroke
				(width 0.1)
				(type default)
			)
			(layer "B.Fab")
		)
		(fp_line
			(start 0.12065 0.2794)
			(end 0.12065 0.3048)
			(stroke
				(width 0.1)
				(type default)
			)
			(layer "B.Fab")
		)
		(fp_line
			(start 0.12065 0.3048)
			(end 0.67945 0.3048)
			(stroke
				(width 0.1)
				(type default)
			)
			(layer "B.Fab")
		)
		(fp_line
			(start 0.67945 -0.305054)
			(end 0.12065 -0.305054)
			(stroke
				(width 0.1)
				(type default)
			)
			(layer "B.Fab")
		)
		(fp_line
			(start 0.67945 0.3048)
			(end 0.67945 -0.305054)
			(stroke
				(width 0.1)
				(type default)
			)
			(layer "B.Fab")
		)
		(pad "1" smd circle
			(at 0.40005 0 180)
			(size 0 0)
			(layers "B.Cu" "B.Mask" "B.Paste")
			(net "P12V_HSC_ADC_N")
		)
		(pad "2" smd circle
			(at -0.40005 0 180)
			(size 0 0)
			(layers "B.Cu" "B.Mask" "B.Paste")
			(net "P12V_HSC_SENSE2_R1_N")
		)
	)
)
